FILE_TYPE = MULTI_PHYS_TABLE;

PART 'NCP380HSNAJAAT1G'

{========================================================================================}
:VALUE              | PART_TYPE | MATERIAL | PART_NUMBER    = STANDARD | LIFECYCLE      | PART_NUMBER   | JEDEC_TYPE | DESCRIPTION                            | MANUFTR | MANUF_PN           | RD_CMPLS_LVL | CMPLS_LVL | FROM_PJ    | CLASS | DIP_SMD | DATA                       | EE_CHECK_LIST | FP_ECN | PSL | CREATOR | STATUS | MSD | ESD_CDM | ESD_HBM | ESD_MM | PIN_LENGTH_SHORT_PIN | PIN_LENGTH_LONG_PIN | CREATEDAY  ;
{========================================================================================}
 'NCP380HSNAJAAT1G' | 'SMLF'    | 'IC'     | 'AL000380K00'(!) = ''       | ''               | 'AL000380K00' |'TSOP6XE'| 'IC OTHER(6P)NCP380HSNAJAAT1G(TSOP-6)' | 'ONS'   | 'NCP380HSNAJAAT1G' | 'EP(V1)'     | 'EP(V1)'  | 'F0C-IVES' | 'IC'  | ''      | 'ONS_NCP380HSNAJAAT1G.pdf' | ''            | ''     | ''  | ''      | ''     | ''  | ''      | ''      | ''     | '0 MILS'             | '0 MILS'            | '20210616'
 'NCP380HSNAJAAT1G' | 'SMLF'    | 'EMPTY'  | 'AL000380K00'(!) = ''       | ''               | 'AL000380K00' |'TSOP6XE'| 'IC OTHER(6P)NCP380HSNAJAAT1G(TSOP-6)' | 'ONS'   | 'NCP380HSNAJAAT1G' | 'EP(V1)'     | 'EP(V1)'  | 'F0C-IVES' | 'IC'  | ''      | 'ONS_NCP380HSNAJAAT1G.pdf' | ''            | ''     | ''  | ''      | ''     | ''  | ''      | ''      | ''     | '0 MILS'             | '0 MILS'            | '20210616'

END_PART

END.

